(kicad_pcb
	(version 20260206)
	(generator "pcbnew")
	(generator_version "10.0")
	(general
		(thickness 1.6)
		(legacy_teardrops no)
	)
	(paper "A4")
	(title_block
		(title "01162023_DA0F0TEBIF0_F0T_Expander_BD_F_brd_V02_OCP.brd")
		(comment 1 "Grand Teton / footprints 8657-8663 of 9728")
	)
	(layers
		(0 "F.Cu" signal "TOP")
		(4 "In1.Cu" signal "GND")
		(6 "In2.Cu" signal "VCC")
		(8 "In3.Cu" signal "VCC1")
		(10 "In4.Cu" signal "GND1")
		(12 "In5.Cu" signal "IN1")
		(14 "In6.Cu" signal "GND2")
		(16 "In7.Cu" signal "IN2")
		(18 "In8.Cu" signal "GND3")
		(20 "In9.Cu" signal "IN3")
		(22 "In10.Cu" signal "GND4")
		(24 "In11.Cu" signal "IN4")
		(26 "In12.Cu" signal "GND5")
		(28 "In13.Cu" signal "IN5")
		(30 "In14.Cu" signal "GND6")
		(32 "In15.Cu" signal "IN6")
		(34 "In16.Cu" signal "GND7")
		(2 "B.Cu" signal "BOTTOM")
		(9 "F.Adhes" user "F.Adhesive")
		(11 "B.Adhes" user "B.Adhesive")
		(13 "F.Paste" user "Package Geometry/Pastemask Top")
		(15 "B.Paste" user "Package Geometry/Pastemask Bottom")
		(5 "F.SilkS" user "Ref Des/Silkscreen Top")
		(7 "B.SilkS" user "Ref Des/Silkscreen Bottom")
		(1 "F.Mask" user "Board Geometry/Soldermask Top")
		(3 "B.Mask" user "Board Geometry/Soldermask Bottom")
		(17 "Dwgs.User" user "User.Drawings")
		(19 "Cmts.User" user "User.Comments")
		(21 "Eco1.User" user "User.Eco1")
		(23 "Eco2.User" user "User.Eco2")
		(25 "Edge.Cuts" user "Board Geometry/Outline")
		(27 "Margin" user)
		(31 "F.CrtYd" user "Package Geometry/Place Bound Top")
		(29 "B.CrtYd" user "Package Geometry/Place Bound Bottom")
		(35 "F.Fab" user "Ref Des/Assembly Top")
		(33 "B.Fab" user "Ref Des/Assembly Bottom")
	)
	(footprint ""
		(layer "B.Cu")
		(at 234.855512 -234.728004 90)
		(property "Reference" "R6185"
			(at 0 0 90)
			(layer "B.SilkS")
			(hide yes)
			(effects
				(font
					(size 1.27 1.27)
				)
				(justify mirror)
			)
		)
		(property "Value" ""
			(at 0 0 90)
			(layer "B.Fab")
			(effects
				(font
					(size 1.27 1.27)
				)
				(justify mirror)
			)
		)
		(duplicate_pad_numbers_are_jumpers no)
		(fp_line
			(start 0.7874 -0.4064)
			(end -0.7874 -0.4064)
			(stroke
				(width 0.1524)
				(type default)
			)
			(layer "B.SilkS")
		)
		(fp_line
			(start -0.7874 -0.4064)
			(end -0.7874 0.4064)
			(stroke
				(width 0.1524)
				(type default)
			)
			(layer "B.SilkS")
		)
		(fp_line
			(start 0.7874 0.4064)
			(end 0.7874 -0.4064)
			(stroke
				(width 0.1524)
				(type default)
			)
			(layer "B.SilkS")
		)
		(fp_line
			(start -0.7874 0.4064)
			(end 0.7874 0.4064)
			(stroke
				(width 0.1524)
				(type default)
			)
			(layer "B.SilkS")
		)
		(fp_line
			(start 0.67945 -0.305054)
			(end 0.12065 -0.305054)
			(stroke
				(width 0.1)
				(type default)
			)
			(layer "B.Fab")
		)
		(fp_line
			(start 0.12065 -0.305054)
			(end 0.12065 -0.2794)
			(stroke
				(width 0.1)
				(type default)
			)
			(layer "B.Fab")
		)
		(fp_line
			(start -0.12065 -0.3048)
			(end -0.67945 -0.3048)
			(stroke
				(width 0.1)
				(type default)
			)
			(layer "B.Fab")
		)
		(fp_line
			(start -0.67945 -0.3048)
			(end -0.67945 0.3048)
			(stroke
				(width 0.1)
				(type default)
			)
			(layer "B.Fab")
		)
		(fp_line
			(start 0.12065 -0.2794)
			(end -0.12065 -0.2794)
			(stroke
				(width 0.1)
				(type default)
			)
			(layer "B.Fab")
		)
		(fp_line
			(start -0.12065 -0.2794)
			(end -0.12065 -0.3048)
			(stroke
				(width 0.1)
				(type default)
			)
			(layer "B.Fab")
		)
		(fp_line
			(start 0.12065 0.2794)
			(end 0.12065 0.3048)
			(stroke
				(width 0.1)
				(type default)
			)
			(layer "B.Fab")
		)
		(fp_line
			(start -0.120396 0.2794)
			(end 0.12065 0.2794)
			(stroke
				(width 0.1)
				(type default)
			)
			(layer "B.Fab")
		)
		(fp_line
			(start 0.67945 0.3048)
			(end 0.67945 -0.305054)
			(stroke
				(width 0.1)
				(type default)
			)
			(layer "B.Fab")
		)
		(fp_line
			(start 0.12065 0.3048)
			(end 0.67945 0.3048)
			(stroke
				(width 0.1)
				(type default)
			)
			(layer "B.Fab")
		)
		(fp_line
			(start -0.120396 0.3048)
			(end -0.120396 0.2794)
			(stroke
				(width 0.1)
				(type default)
			)
			(layer "B.Fab")
		)
		(fp_line
			(start -0.67945 0.3048)
			(end -0.120396 0.3048)
			(stroke
				(width 0.1)
				(type default)
			)
			(layer "B.Fab")
		)
		(pad "1" smd circle
			(at 0.40005 0 270)
			(size 0 0)
			(layers "B.Cu" "B.Mask" "B.Paste")
			(net "GND")
		)
		(pad "2" smd circle
			(at -0.40005 0 270)
			(size 0 0)
			(layers "B.Cu" "B.Mask" "B.Paste")
			(net "SSD3_PWRDIS_BIC_R")
		)
	)
	(footprint ""
		(layer "B.Cu")
		(at 171.474892 -297.79976 90)
		(property "Reference" "C1403"
			(at 0 0 90)
			(layer "B.SilkS")
			(hide yes)
			(effects
				(font
					(size 1.27 1.27)
				)
				(justify mirror)
			)
		)
		(property "Value" ""
			(at 0 0 90)
			(layer "B.Fab")
			(effects
				(font
					(size 1.27 1.27)
				)
				(justify mirror)
			)
		)
		(duplicate_pad_numbers_are_jumpers no)
		(fp_line
			(start 0.299974 -0.150114)
			(end -0.299974 -0.150114)
			(stroke
				(width 0.1)
				(type default)
			)
			(layer "B.Fab")
		)
		(fp_line
			(start -0.299974 -0.150114)
			(end -0.299974 0.150114)
			(stroke
				(width 0.1)
				(type default)
			)
			(layer "B.Fab")
		)
		(fp_line
			(start 0.299974 0.150114)
			(end 0.299974 -0.150114)
			(stroke
				(width 0.1)
				(type default)
			)
			(layer "B.Fab")
		)
		(fp_line
			(start -0.299974 0.150114)
			(end 0.299974 0.150114)
			(stroke
				(width 0.1)
				(type default)
			)
			(layer "B.Fab")
		)
		(pad "1" smd rect
			(at 0.2667 0 270)
			(size 0.3048 0.381)
			(layers "B.Cu" "B.Mask" "B.Paste")
			(net "P0V8_PEX1")
		)
		(pad "2" smd rect
			(at -0.2667 0 270)
			(size 0.3048 0.381)
			(layers "B.Cu" "B.Mask" "B.Paste")
			(net "GND")
		)
	)
	(footprint ""
		(layer "B.Cu")
		(at 77.541882 -103.104696 180)
		(property "Reference" "R67"
			(at 0 0 0)
			(layer "B.SilkS")
			(hide yes)
			(effects
				(font
					(size 1.27 1.27)
				)
				(justify mirror)
			)
		)
		(property "Value" ""
			(at 0 0 0)
			(layer "B.Fab")
			(effects
				(font
					(size 1.27 1.27)
				)
				(justify mirror)
			)
		)
		(duplicate_pad_numbers_are_jumpers no)
		(fp_line
			(start 0.7874 0.4064)
			(end 0.7874 -0.4064)
			(stroke
				(width 0.1524)
				(type default)
			)
			(layer "B.SilkS")
		)
		(fp_line
			(start 0.7874 -0.4064)
			(end -0.7874 -0.4064)
			(stroke
				(width 0.1524)
				(type default)
			)
			(layer "B.SilkS")
		)
		(fp_line
			(start -0.7874 0.4064)
			(end 0.7874 0.4064)
			(stroke
				(width 0.1524)
				(type default)
			)
			(layer "B.SilkS")
		)
		(fp_line
			(start -0.7874 -0.4064)
			(end -0.7874 0.4064)
			(stroke
				(width 0.1524)
				(type default)
			)
			(layer "B.SilkS")
		)
		(fp_line
			(start 0.67945 0.3048)
			(end 0.67945 -0.305054)
			(stroke
				(width 0.1)
				(type default)
			)
			(layer "B.Fab")
		)
		(fp_line
			(start 0.67945 -0.305054)
			(end 0.12065 -0.305054)
			(stroke
				(width 0.1)
				(type default)
			)
			(layer "B.Fab")
		)
		(fp_line
			(start 0.12065 0.3048)
			(end 0.67945 0.3048)
			(stroke
				(width 0.1)
				(type default)
			)
			(layer "B.Fab")
		)
		(fp_line
			(start 0.12065 0.2794)
			(end 0.12065 0.3048)
			(stroke
				(width 0.1)
				(type default)
			)
			(layer "B.Fab")
		)
		(fp_line
			(start 0.12065 -0.2794)
			(end -0.12065 -0.2794)
			(stroke
				(width 0.1)
				(type default)
			)
			(layer "B.Fab")
		)
		(fp_line
			(start 0.12065 -0.305054)
			(end 0.12065 -0.2794)
			(stroke
				(width 0.1)
				(type default)
			)
			(layer "B.Fab")
		)
		(fp_line
			(start -0.120396 0.3048)
			(end -0.120396 0.2794)
			(stroke
				(width 0.1)
				(type default)
			)
			(layer "B.Fab")
		)
		(fp_line
			(start -0.120396 0.2794)
			(end 0.12065 0.2794)
			(stroke
				(width 0.1)
				(type default)
			)
			(layer "B.Fab")
		)
		(fp_line
			(start -0.12065 -0.2794)
			(end -0.12065 -0.3048)
			(stroke
				(width 0.1)
				(type default)
			)
			(layer "B.Fab")
		)
		(fp_line
			(start -0.12065 -0.3048)
			(end -0.67945 -0.3048)
			(stroke
				(width 0.1)
				(type default)
			)
			(layer "B.Fab")
		)
		(fp_line
			(start -0.67945 0.3048)
			(end -0.120396 0.3048)
			(stroke
				(width 0.1)
				(type default)
			)
			(layer "B.Fab")
		)
		(fp_line
			(start -0.67945 -0.3048)
			(end -0.67945 0.3048)
			(stroke
				(width 0.1)
				(type default)
			)
			(layer "B.Fab")
		)
		(pad "1" smd circle
			(at 0.40005 0)
			(size 0 0)
			(layers "B.Cu" "B.Mask" "B.Paste")
			(net "NCSI_NIC1_RXD0")
		)
		(pad "2" smd circle
			(at -0.40005 0)
			(size 0 0)
			(layers "B.Cu" "B.Mask" "B.Paste")
			(net "GND")
		)
	)
	(footprint ""
		(layer "B.Cu")
		(at 397.85544 -153.0096)
		(property "Reference" "R325"
			(at 0 0 0)
			(layer "B.SilkS")
			(hide yes)
			(effects
				(font
					(size 1.27 1.27)
				)
				(justify mirror)
			)
		)
		(property "Value" ""
			(at 0 0 0)
			(layer "B.Fab")
			(effects
				(font
					(size 1.27 1.27)
				)
				(justify mirror)
			)
		)
		(duplicate_pad_numbers_are_jumpers no)
		(fp_line
			(start -0.7874 -0.4064)
			(end -0.7874 0.4064)
			(stroke
				(width 0.1524)
				(type default)
			)
			(layer "B.SilkS")
		)
		(fp_line
			(start -0.7874 0.4064)
			(end 0.7874 0.4064)
			(stroke
				(width 0.1524)
				(type default)
			)
			(layer "B.SilkS")
		)
		(fp_line
			(start 0.7874 -0.4064)
			(end -0.7874 -0.4064)
			(stroke
				(width 0.1524)
				(type default)
			)
			(layer "B.SilkS")
		)
		(fp_line
			(start 0.7874 0.4064)
			(end 0.7874 -0.4064)
			(stroke
				(width 0.1524)
				(type default)
			)
			(layer "B.SilkS")
		)
		(fp_line
			(start -0.67945 -0.3048)
			(end -0.67945 0.3048)
			(stroke
				(width 0.1)
				(type default)
			)
			(layer "B.Fab")
		)
		(fp_line
			(start -0.67945 0.3048)
			(end -0.120396 0.3048)
			(stroke
				(width 0.1)
				(type default)
			)
			(layer "B.Fab")
		)
		(fp_line
			(start -0.12065 -0.3048)
			(end -0.67945 -0.3048)
			(stroke
				(width 0.1)
				(type default)
			)
			(layer "B.Fab")
		)
		(fp_line
			(start -0.12065 -0.2794)
			(end -0.12065 -0.3048)
			(stroke
				(width 0.1)
				(type default)
			)
			(layer "B.Fab")
		)
		(fp_line
			(start -0.120396 0.2794)
			(end 0.12065 0.2794)
			(stroke
				(width 0.1)
				(type default)
			)
			(layer "B.Fab")
		)
		(fp_line
			(start -0.120396 0.3048)
			(end -0.120396 0.2794)
			(stroke
				(width 0.1)
				(type default)
			)
			(layer "B.Fab")
		)
		(fp_line
			(start 0.12065 -0.305054)
			(end 0.12065 -0.2794)
			(stroke
				(width 0.1)
				(type default)
			)
			(layer "B.Fab")
		)
		(fp_line
			(start 0.12065 -0.2794)
			(end -0.12065 -0.2794)
			(stroke
				(width 0.1)
				(type default)
			)
			(layer "B.Fab")
		)
		(fp_line
			(start 0.12065 0.2794)
			(end 0.12065 0.3048)
			(stroke
				(width 0.1)
				(type default)
			)
			(layer "B.Fab")
		)
		(fp_line
			(start 0.12065 0.3048)
			(end 0.67945 0.3048)
			(stroke
				(width 0.1)
				(type default)
			)
			(layer "B.Fab")
		)
		(fp_line
			(start 0.67945 -0.305054)
			(end 0.12065 -0.305054)
			(stroke
				(width 0.1)
				(type default)
			)
			(layer "B.Fab")
		)
		(fp_line
			(start 0.67945 0.3048)
			(end 0.67945 -0.305054)
			(stroke
				(width 0.1)
				(type default)
			)
			(layer "B.Fab")
		)
		(pad "1" smd circle
			(at 0.40005 0 180)
			(size 0 0)
			(layers "B.Cu" "B.Mask" "B.Paste")
			(net "NCSI_NIC6_TXD1")
		)
		(pad "2" smd circle
			(at -0.40005 0 180)
			(size 0 0)
			(layers "B.Cu" "B.Mask" "B.Paste")
			(net "GND")
		)
	)
	(footprint ""
		(layer "B.Cu")
		(at 231.86771 -219.904056)
		(property "Reference" "C3610"
			(at 0 0 0)
			(layer "B.SilkS")
			(hide yes)
			(effects
				(font
					(size 1.27 1.27)
				)
				(justify mirror)
			)
		)
		(property "Value" ""
			(at 0 0 0)
			(layer "B.Fab")
			(effects
				(font
					(size 1.27 1.27)
				)
				(justify mirror)
			)
		)
		(duplicate_pad_numbers_are_jumpers no)
		(fp_line
			(start -0.69215 -0.2921)
			(end -0.69215 0.2921)
			(stroke
				(width 0.1524)
				(type default)
			)
			(layer "B.SilkS")
		)
		(fp_line
			(start -0.69215 0.2921)
			(end 0.69215 0.2921)
			(stroke
				(width 0.1524)
				(type default)
			)
			(layer "B.SilkS")
		)
		(fp_line
			(start 0.69215 -0.2921)
			(end -0.69215 -0.2921)
			(stroke
				(width 0.1524)
				(type default)
			)
			(layer "B.SilkS")
		)
		(fp_line
			(start 0.69215 0.2921)
			(end 0.69215 -0.2921)
			(stroke
				(width 0.1524)
				(type default)
			)
			(layer "B.SilkS")
		)
		(fp_line
			(start -0.51435 -0.2794)
			(end -0.51435 0.2794)
			(stroke
				(width 0.1)
				(type default)
			)
			(layer "B.Fab")
		)
		(fp_line
			(start -0.51435 0.2794)
			(end 0.51435 0.2794)
			(stroke
				(width 0.1)
				(type default)
			)
			(layer "B.Fab")
		)
		(fp_line
			(start 0.51435 -0.2794)
			(end -0.51435 -0.2794)
			(stroke
				(width 0.1)
				(type default)
			)
			(layer "B.Fab")
		)
		(fp_line
			(start 0.51435 0.2794)
			(end 0.51435 -0.2794)
			(stroke
				(width 0.1)
				(type default)
			)
			(layer "B.Fab")
		)
		(pad "1" smd circle
			(at 0.40005 0 180)
			(size 0 0)
			(layers "B.Cu" "B.Mask" "B.Paste")
			(net "P3V3_BIC_ADCAV33")
		)
		(pad "2" smd circle
			(at -0.40005 0 180)
			(size 0 0)
			(layers "B.Cu" "B.Mask" "B.Paste")
			(net "GND")
		)
		(zone
			(layer "B.Cu")
			(hatch none 0.5)
			(connect_pads
				(clearance 0)
			)
			(min_thickness 0.25)
			(keepout
				(tracks not_allowed)
				(vias allowed)
				(pads allowed)
				(copperpour not_allowed)
				(footprints allowed)
			)
			(placement
				(enabled no)
				(sheetname "")
			)
			(fill
				(thermal_gap 0.5)
				(thermal_bridge_width 0.5)
				(island_removal_mode 0)
			)
			(polygon
				(pts
					(xy 232.05821 -219.816426) (xy 231.96677 -219.75826) (xy 231.76738 -219.75826) (xy 231.67721 -219.816426)
					(xy 231.67721 -219.991686) (xy 231.76738 -220.050106) (xy 231.96677 -220.050106) (xy 232.05821 -219.99194)
				)
			)
		)
	)
	(footprint ""
		(layer "B.Cu")
		(at 379.847602 -243.428012 180)
		(property "Reference" "R931"
			(at 0 0 0)
			(layer "B.SilkS")
			(hide yes)
			(effects
				(font
					(size 1.27 1.27)
				)
				(justify mirror)
			)
		)
		(property "Value" ""
			(at 0 0 0)
			(layer "B.Fab")
			(effects
				(font
					(size 1.27 1.27)
				)
				(justify mirror)
			)
		)
		(duplicate_pad_numbers_are_jumpers no)
		(fp_line
			(start 0.7874 0.4064)
			(end 0.7874 -0.4064)
			(stroke
				(width 0.1524)
				(type default)
			)
			(layer "B.SilkS")
		)
		(fp_line
			(start 0.7874 -0.4064)
			(end -0.7874 -0.4064)
			(stroke
				(width 0.1524)
				(type default)
			)
			(layer "B.SilkS")
		)
		(fp_line
			(start -0.7874 0.4064)
			(end 0.7874 0.4064)
			(stroke
				(width 0.1524)
				(type default)
			)
			(layer "B.SilkS")
		)
		(fp_line
			(start -0.7874 -0.4064)
			(end -0.7874 0.4064)
			(stroke
				(width 0.1524)
				(type default)
			)
			(layer "B.SilkS")
		)
		(fp_line
			(start 0.67945 0.3048)
			(end 0.67945 -0.305054)
			(stroke
				(width 0.1)
				(type default)
			)
			(layer "B.Fab")
		)
		(fp_line
			(start 0.67945 -0.305054)
			(end 0.12065 -0.305054)
			(stroke
				(width 0.1)
				(type default)
			)
			(layer "B.Fab")
		)
		(fp_line
			(start 0.12065 0.3048)
			(end 0.67945 0.3048)
			(stroke
				(width 0.1)
				(type default)
			)
			(layer "B.Fab")
		)
		(fp_line
			(start 0.12065 0.2794)
			(end 0.12065 0.3048)
			(stroke
				(width 0.1)
				(type default)
			)
			(layer "B.Fab")
		)
		(fp_line
			(start 0.12065 -0.2794)
			(end -0.12065 -0.2794)
			(stroke
				(width 0.1)
				(type default)
			)
			(layer "B.Fab")
		)
		(fp_line
			(start 0.12065 -0.305054)
			(end 0.12065 -0.2794)
			(stroke
				(width 0.1)
				(type default)
			)
			(layer "B.Fab")
		)
		(fp_line
			(start -0.120396 0.3048)
			(end -0.120396 0.2794)
			(stroke
				(width 0.1)
				(type default)
			)
			(layer "B.Fab")
		)
		(fp_line
			(start -0.120396 0.2794)
			(end 0.12065 0.2794)
			(stroke
				(width 0.1)
				(type default)
			)
			(layer "B.Fab")
		)
		(fp_line
			(start -0.12065 -0.2794)
			(end -0.12065 -0.3048)
			(stroke
				(width 0.1)
				(type default)
			)
			(layer "B.Fab")
		)
		(fp_line
			(start -0.12065 -0.3048)
			(end -0.67945 -0.3048)
			(stroke
				(width 0.1)
				(type default)
			)
			(layer "B.Fab")
		)
		(fp_line
			(start -0.67945 0.3048)
			(end -0.120396 0.3048)
			(stroke
				(width 0.1)
				(type default)
			)
			(layer "B.Fab")
		)
		(fp_line
			(start -0.67945 -0.3048)
			(end -0.67945 0.3048)
			(stroke
				(width 0.1)
				(type default)
			)
			(layer "B.Fab")
		)
		(pad "1" smd circle
			(at 0.40005 0)
			(size 0 0)
			(layers "B.Cu" "B.Mask" "B.Paste")
			(net "UART_PEX0_SDB_BUF_TX")
		)
		(pad "2" smd circle
			(at -0.40005 0)
			(size 0 0)
			(layers "B.Cu" "B.Mask" "B.Paste")
			(net "P3V3_AUX")
		)
	)
	(footprint ""
		(layer "B.Cu")
		(at 344.83802 -308.613556 90)
		(property "Reference" "C4305"
			(at 0 0 90)
			(layer "B.SilkS")
			(hide yes)
			(effects
				(font
					(size 1.27 1.27)
				)
				(justify mirror)
			)
		)
		(property "Value" ""
			(at 0 0 90)
			(layer "B.Fab")
			(effects
				(font
					(size 1.27 1.27)
				)
				(justify mirror)
			)
		)
		(duplicate_pad_numbers_are_jumpers no)
		(fp_line
			(start 1.2954 -0.5842)
			(end -1.2954 -0.5842)
			(stroke
				(width 0.1524)
				(type default)
			)
			(layer "B.SilkS")
		)
		(fp_line
			(start -1.2954 -0.5842)
			(end -1.2954 0.5842)
			(stroke
				(width 0.1524)
				(type default)
			)
			(layer "B.SilkS")
		)
		(fp_line
			(start 1.2954 0.5842)
			(end 1.2954 -0.5842)
			(stroke
				(width 0.1524)
				(type default)
			)
			(layer "B.SilkS")
		)
		(fp_line
			(start -1.2954 0.5842)
			(end 1.2954 0.5842)
			(stroke
				(width 0.1524)
				(type default)
			)
			(layer "B.SilkS")
		)
		(fp_line
			(start 0.8636 -0.4572)
			(end -0.8636 -0.4572)
			(stroke
				(width 0.1)
				(type default)
			)
			(layer "B.Fab")
		)
		(fp_line
			(start -0.8636 -0.4572)
			(end -0.8636 -0.4064)
			(stroke
				(width 0.1)
				(type default)
			)
			(layer "B.Fab")
		)
		(fp_line
			(start 1.1938 -0.4064)
			(end 0.8636 -0.4064)
			(stroke
				(width 0.1)
				(type default)
			)
			(layer "B.Fab")
		)
		(fp_line
			(start 0.8636 -0.4064)
			(end 0.8636 -0.4572)
			(stroke
				(width 0.1)
				(type default)
			)
			(layer "B.Fab")
		)
		(fp_line
			(start -0.8636 -0.4064)
			(end -1.1938 -0.4064)
			(stroke
				(width 0.1)
				(type default)
			)
			(layer "B.Fab")
		)
		(fp_line
			(start -1.1938 -0.4064)
			(end -1.1938 0.4064)
			(stroke
				(width 0.1)
				(type default)
			)
			(layer "B.Fab")
		)
		(fp_line
			(start 1.1938 0.4064)
			(end 1.1938 -0.4064)
			(stroke
				(width 0.1)
				(type default)
			)
			(layer "B.Fab")
		)
		(fp_line
			(start 0.8636 0.4064)
			(end 1.1938 0.4064)
			(stroke
				(width 0.1)
				(type default)
			)
			(layer "B.Fab")
		)
		(fp_line
			(start -0.8636 0.4064)
			(end -0.8636 0.4572)
			(stroke
				(width 0.1)
				(type default)
			)
			(layer "B.Fab")
		)
		(fp_line
			(start -1.1938 0.4064)
			(end -0.8636 0.4064)
			(stroke
				(width 0.1)
				(type default)
			)
			(layer "B.Fab")
		)
		(fp_line
			(start 0.8636 0.4572)
			(end 0.8636 0.4064)
			(stroke
				(width 0.1)
				(type default)
			)
			(layer "B.Fab")
		)
		(fp_line
			(start -0.8636 0.4572)
			(end 0.8636 0.4572)
			(stroke
				(width 0.1)
				(type default)
			)
			(layer "B.Fab")
		)
		(pad "1" smd rect
			(at 0.7366 0)
			(size 0.7112 0.8128)
			(layers "B.Cu" "B.Mask" "B.Paste")
			(net "P0V8_PEX2")
		)
		(pad "2" smd rect
			(at -0.7366 0)
			(size 0.7112 0.8128)
			(layers "B.Cu" "B.Mask" "B.Paste")
			(net "GND")
		)
	)
)
